(kicad_pcb
	(version 20260206)
	(generator "pcbnew")
	(generator_version "10.0")
	(general
		(thickness 1.6)
		(legacy_teardrops no)
	)
	(paper "A4")
	(title_block
		(title "01162023_DA0F0TEBIF0_F0T_Expander_BD_F_brd_V02_OCP.brd")
		(comment 1 "Grand Teton / footprints 6620-6626 of 9728")
	)
	(layers
		(0 "F.Cu" signal "TOP")
		(4 "In1.Cu" signal "GND")
		(6 "In2.Cu" signal "VCC")
		(8 "In3.Cu" signal "VCC1")
		(10 "In4.Cu" signal "GND1")
		(12 "In5.Cu" signal "IN1")
		(14 "In6.Cu" signal "GND2")
		(16 "In7.Cu" signal "IN2")
		(18 "In8.Cu" signal "GND3")
		(20 "In9.Cu" signal "IN3")
		(22 "In10.Cu" signal "GND4")
		(24 "In11.Cu" signal "IN4")
		(26 "In12.Cu" signal "GND5")
		(28 "In13.Cu" signal "IN5")
		(30 "In14.Cu" signal "GND6")
		(32 "In15.Cu" signal "IN6")
		(34 "In16.Cu" signal "GND7")
		(2 "B.Cu" signal "BOTTOM")
		(9 "F.Adhes" user "F.Adhesive")
		(11 "B.Adhes" user "B.Adhesive")
		(13 "F.Paste" user "Package Geometry/Pastemask Top")
		(15 "B.Paste" user "Package Geometry/Pastemask Bottom")
		(5 "F.SilkS" user "Ref Des/Silkscreen Top")
		(7 "B.SilkS" user "Ref Des/Silkscreen Bottom")
		(1 "F.Mask" user "Board Geometry/Soldermask Top")
		(3 "B.Mask" user "Board Geometry/Soldermask Bottom")
		(17 "Dwgs.User" user "User.Drawings")
		(19 "Cmts.User" user "User.Comments")
		(21 "Eco1.User" user "User.Eco1")
		(23 "Eco2.User" user "User.Eco2")
		(25 "Edge.Cuts" user "Board Geometry/Outline")
		(27 "Margin" user)
		(31 "F.CrtYd" user "Package Geometry/Place Bound Top")
		(29 "B.CrtYd" user "Package Geometry/Place Bound Bottom")
		(35 "F.Fab" user "Ref Des/Assembly Top")
		(33 "B.Fab" user "Ref Des/Assembly Bottom")
	)
	(footprint ""
		(layer "F.Cu")
		(at 271.480534 -121.005346)
		(property "Reference" "C467"
			(at 0 0 0)
			(layer "F.SilkS")
			(hide yes)
			(effects
				(font
					(size 1.27 1.27)
				)
			)
		)
		(property "Value" ""
			(at 0 0 0)
			(layer "F.Fab")
			(effects
				(font
					(size 1.27 1.27)
				)
			)
		)
		(duplicate_pad_numbers_are_jumpers no)
		(fp_line
			(start -0.299974 -0.150114)
			(end 0.299974 -0.150114)
			(stroke
				(width 0.1)
				(type default)
			)
			(layer "F.Fab")
		)
		(fp_line
			(start -0.299974 0.150114)
			(end -0.299974 -0.150114)
			(stroke
				(width 0.1)
				(type default)
			)
			(layer "F.Fab")
		)
		(fp_line
			(start 0.299974 -0.150114)
			(end 0.299974 0.150114)
			(stroke
				(width 0.1)
				(type default)
			)
			(layer "F.Fab")
		)
		(fp_line
			(start 0.299974 0.150114)
			(end -0.299974 0.150114)
			(stroke
				(width 0.1)
				(type default)
			)
			(layer "F.Fab")
		)
		(pad "1" smd rect
			(at -0.2667 0)
			(size 0.3048 0.381)
			(layers "F.Cu" "F.Mask" "F.Paste")
			(net "P5E_PEX2_STN1_TX_DN<25>")
		)
		(pad "2" smd rect
			(at 0.2667 0)
			(size 0.3048 0.381)
			(layers "F.Cu" "F.Mask" "F.Paste")
			(net "P5E_PEX2_STN1_TX_C_DN<25>")
		)
	)
	(footprint ""
		(layer "F.Cu")
		(at 104.65816 -212.783166 90)
		(property "Reference" "PL25"
			(at -0.286766 -1.32969 90)
			(unlocked yes)
			(layer "F.SilkS")
			(effects
				(font
					(size 0.7874 0.5842)
					(thickness 0.1524)
				)
			)
		)
		(property "Value" ""
			(at 0 0 90)
			(layer "F.Fab")
			(effects
				(font
					(size 1.27 1.27)
				)
			)
		)
		(duplicate_pad_numbers_are_jumpers no)
		(fp_line
			(start -1.27 -0.5842)
			(end 1.27 -0.5842)
			(stroke
				(width 0.1524)
				(type default)
			)
			(layer "F.SilkS")
		)
		(fp_line
			(start -1.27 -0.5588)
			(end -1.27 -0.5842)
			(stroke
				(width 0.1524)
				(type default)
			)
			(layer "F.SilkS")
		)
		(fp_line
			(start 1.27 0.5842)
			(end 1.27 -0.5842)
			(stroke
				(width 0.1524)
				(type default)
			)
			(layer "F.SilkS")
		)
		(fp_line
			(start 1.27 0.5842)
			(end -1.27 0.5842)
			(stroke
				(width 0.1524)
				(type default)
			)
			(layer "F.SilkS")
		)
		(fp_line
			(start -1.27 0.5842)
			(end -1.27 -0.5842)
			(stroke
				(width 0.1524)
				(type default)
			)
			(layer "F.SilkS")
		)
		(fp_line
			(start 0.9144 -0.508)
			(end 0.9144 -0.406654)
			(stroke
				(width 0.1)
				(type default)
			)
			(layer "F.Fab")
		)
		(fp_line
			(start -0.9144 -0.508)
			(end 0.9144 -0.508)
			(stroke
				(width 0.1)
				(type default)
			)
			(layer "F.Fab")
		)
		(fp_line
			(start 1.1938 -0.406654)
			(end 1.1938 0.4064)
			(stroke
				(width 0.1)
				(type default)
			)
			(layer "F.Fab")
		)
		(fp_line
			(start 0.9144 -0.406654)
			(end 1.1938 -0.406654)
			(stroke
				(width 0.1)
				(type default)
			)
			(layer "F.Fab")
		)
		(fp_line
			(start -0.9144 -0.406654)
			(end -0.9144 -0.508)
			(stroke
				(width 0.1)
				(type default)
			)
			(layer "F.Fab")
		)
		(fp_line
			(start -1.194308 -0.406654)
			(end -0.9144 -0.406654)
			(stroke
				(width 0.1)
				(type default)
			)
			(layer "F.Fab")
		)
		(fp_line
			(start 1.1938 0.4064)
			(end 0.9144 0.4064)
			(stroke
				(width 0.1)
				(type default)
			)
			(layer "F.Fab")
		)
		(fp_line
			(start 0.9144 0.4064)
			(end 0.9144 0.508)
			(stroke
				(width 0.1)
				(type default)
			)
			(layer "F.Fab")
		)
		(fp_line
			(start -0.9144 0.406654)
			(end -1.194308 0.406654)
			(stroke
				(width 0.1)
				(type default)
			)
			(layer "F.Fab")
		)
		(fp_line
			(start -1.194308 0.406654)
			(end -1.194308 -0.406654)
			(stroke
				(width 0.1)
				(type default)
			)
			(layer "F.Fab")
		)
		(fp_line
			(start 0.9144 0.508)
			(end -0.9144 0.508)
			(stroke
				(width 0.1)
				(type default)
			)
			(layer "F.Fab")
		)
		(fp_line
			(start -0.9144 0.508)
			(end -0.9144 0.406654)
			(stroke
				(width 0.1)
				(type default)
			)
			(layer "F.Fab")
		)
		(pad "1" smd rect
			(at -0.7366 0)
			(size 0.7112 0.8128)
			(layers "F.Cu" "F.Mask" "F.Paste")
			(net "P12V_AUX")
		)
		(pad "2" smd rect
			(at 0.7366 0)
			(size 0.7112 0.8128)
			(layers "F.Cu" "F.Mask" "F.Paste")
			(net "SW_P12V_P1V8_PEX_FLT")
		)
	)
	(footprint ""
		(layer "F.Cu")
		(at 4.150106 -365.193072 90)
		(property "Reference" "Q250"
			(at -1.651 -2.25933 90)
			(unlocked yes)
			(layer "F.SilkS")
			(effects
				(font
					(size 0.7874 0.5842)
					(thickness 0.1524)
				)
				(justify left)
			)
		)
		(property "Value" ""
			(at 0 0 90)
			(layer "F.Fab")
			(effects
				(font
					(size 1.27 1.27)
				)
			)
		)
		(duplicate_pad_numbers_are_jumpers no)
		(fp_line
			(start 1.603248 -1.500124)
			(end 1.603248 1.500124)
			(stroke
				(width 0.1524)
				(type default)
			)
			(layer "F.SilkS")
		)
		(fp_line
			(start -1.603248 -1.500124)
			(end 1.603248 -1.500124)
			(stroke
				(width 0.1524)
				(type default)
			)
			(layer "F.SilkS")
		)
		(fp_line
			(start 1.603248 1.500124)
			(end -1.603248 1.500124)
			(stroke
				(width 0.1524)
				(type default)
			)
			(layer "F.SilkS")
		)
		(fp_line
			(start -1.603248 1.500124)
			(end -1.603248 -1.500124)
			(stroke
				(width 0.1524)
				(type default)
			)
			(layer "F.SilkS")
		)
		(fp_line
			(start 0.700024 -1.500124)
			(end -0.700024 -1.500124)
			(stroke
				(width 0.1)
				(type default)
			)
			(layer "F.Fab")
		)
		(fp_line
			(start -0.700024 -1.500124)
			(end -0.700024 -1.169924)
			(stroke
				(width 0.1)
				(type default)
			)
			(layer "F.Fab")
		)
		(fp_line
			(start -0.700024 -1.169924)
			(end -1.249934 -1.169924)
			(stroke
				(width 0.1)
				(type default)
			)
			(layer "F.Fab")
		)
		(fp_line
			(start -1.249934 -1.169924)
			(end -1.249934 -0.729996)
			(stroke
				(width 0.1)
				(type default)
			)
			(layer "F.Fab")
		)
		(fp_line
			(start -0.6985 -0.729996)
			(end -0.6985 0.729996)
			(stroke
				(width 0.1)
				(type default)
			)
			(layer "F.Fab")
		)
		(fp_line
			(start -1.249934 -0.729996)
			(end -0.6985 -0.729996)
			(stroke
				(width 0.1)
				(type default)
			)
			(layer "F.Fab")
		)
		(fp_line
			(start 1.249934 -0.219964)
			(end 0.700024 -0.219964)
			(stroke
				(width 0.1)
				(type default)
			)
			(layer "F.Fab")
		)
		(fp_line
			(start 0.700024 -0.219964)
			(end 0.700024 -1.500124)
			(stroke
				(width 0.1)
				(type default)
			)
			(layer "F.Fab")
		)
		(fp_line
			(start 1.249934 0.219964)
			(end 1.249934 -0.219964)
			(stroke
				(width 0.1)
				(type default)
			)
			(layer "F.Fab")
		)
		(fp_line
			(start 0.700024 0.219964)
			(end 1.249934 0.219964)
			(stroke
				(width 0.1)
				(type default)
			)
			(layer "F.Fab")
		)
		(fp_line
			(start -0.6985 0.729996)
			(end -1.249934 0.729996)
			(stroke
				(width 0.1)
				(type default)
			)
			(layer "F.Fab")
		)
		(fp_line
			(start -1.249934 0.729996)
			(end -1.249934 1.169924)
			(stroke
				(width 0.1)
				(type default)
			)
			(layer "F.Fab")
		)
		(fp_line
			(start -0.700024 1.169924)
			(end -0.700024 1.500124)
			(stroke
				(width 0.1)
				(type default)
			)
			(layer "F.Fab")
		)
		(fp_line
			(start -1.249934 1.169924)
			(end -0.700024 1.169924)
			(stroke
				(width 0.1)
				(type default)
			)
			(layer "F.Fab")
		)
		(fp_line
			(start 0.700024 1.500124)
			(end 0.700024 0.219964)
			(stroke
				(width 0.1)
				(type default)
			)
			(layer "F.Fab")
		)
		(fp_line
			(start -0.700024 1.500124)
			(end 0.700024 1.500124)
			(stroke
				(width 0.1)
				(type default)
			)
			(layer "F.Fab")
		)
		(fp_rect
			(start -0.700024 1.500124)
			(end 0.700024 -1.500124)
			(stroke
				(width 0)
				(type default)
			)
			(fill no)
			(layer "F.Fab")
		)
		(pad "D" smd rect
			(at 0.999998 0)
			(size 0.8128 0.9144)
			(layers "F.Cu" "F.Mask" "F.Paste")
			(net "PG12_USB_HUB_N")
		)
		(pad "G" smd rect
			(at -0.999998 -0.94996)
			(size 0.8128 0.9144)
			(layers "F.Cu" "F.Mask" "F.Paste")
			(net "P1V2_USB_8042")
		)
		(pad "S" smd rect
			(at -0.999998 0.94996)
			(size 0.8128 0.9144)
			(layers "F.Cu" "F.Mask" "F.Paste")
			(net "GND")
		)
	)
	(footprint ""
		(layer "F.Cu")
		(at 106.787188 -92.368878 -90)
		(property "Reference" "R1131"
			(at 0 0 270)
			(layer "F.SilkS")
			(hide yes)
			(effects
				(font
					(size 1.27 1.27)
				)
			)
		)
		(property "Value" ""
			(at 0 0 270)
			(layer "F.Fab")
			(effects
				(font
					(size 1.27 1.27)
				)
			)
		)
		(duplicate_pad_numbers_are_jumpers no)
		(fp_line
			(start -0.7874 0.4064)
			(end -0.7874 -0.4064)
			(stroke
				(width 0.1524)
				(type default)
			)
			(layer "F.SilkS")
		)
		(fp_line
			(start 0.7874 0.4064)
			(end -0.7874 0.4064)
			(stroke
				(width 0.1524)
				(type default)
			)
			(layer "F.SilkS")
		)
		(fp_line
			(start -0.7874 -0.4064)
			(end 0.7874 -0.4064)
			(stroke
				(width 0.1524)
				(type default)
			)
			(layer "F.SilkS")
		)
		(fp_line
			(start 0.7874 -0.4064)
			(end 0.7874 0.4064)
			(stroke
				(width 0.1524)
				(type default)
			)
			(layer "F.SilkS")
		)
		(fp_line
			(start -0.67945 0.3048)
			(end -0.67945 -0.305054)
			(stroke
				(width 0.1)
				(type default)
			)
			(layer "F.Fab")
		)
		(fp_line
			(start -0.12065 0.3048)
			(end -0.67945 0.3048)
			(stroke
				(width 0.1)
				(type default)
			)
			(layer "F.Fab")
		)
		(fp_line
			(start 0.120396 0.3048)
			(end 0.120396 0.2794)
			(stroke
				(width 0.1)
				(type default)
			)
			(layer "F.Fab")
		)
		(fp_line
			(start 0.67945 0.3048)
			(end 0.120396 0.3048)
			(stroke
				(width 0.1)
				(type default)
			)
			(layer "F.Fab")
		)
		(fp_line
			(start -0.12065 0.2794)
			(end -0.12065 0.3048)
			(stroke
				(width 0.1)
				(type default)
			)
			(layer "F.Fab")
		)
		(fp_line
			(start 0.120396 0.2794)
			(end -0.12065 0.2794)
			(stroke
				(width 0.1)
				(type default)
			)
			(layer "F.Fab")
		)
		(fp_line
			(start -0.12065 -0.2794)
			(end 0.12065 -0.2794)
			(stroke
				(width 0.1)
				(type default)
			)
			(layer "F.Fab")
		)
		(fp_line
			(start 0.12065 -0.2794)
			(end 0.12065 -0.3048)
			(stroke
				(width 0.1)
				(type default)
			)
			(layer "F.Fab")
		)
		(fp_line
			(start 0.12065 -0.3048)
			(end 0.67945 -0.3048)
			(stroke
				(width 0.1)
				(type default)
			)
			(layer "F.Fab")
		)
		(fp_line
			(start 0.67945 -0.3048)
			(end 0.67945 0.3048)
			(stroke
				(width 0.1)
				(type default)
			)
			(layer "F.Fab")
		)
		(fp_line
			(start -0.67945 -0.305054)
			(end -0.12065 -0.305054)
			(stroke
				(width 0.1)
				(type default)
			)
			(layer "F.Fab")
		)
		(fp_line
			(start -0.12065 -0.305054)
			(end -0.12065 -0.2794)
			(stroke
				(width 0.1)
				(type default)
			)
			(layer "F.Fab")
		)
		(pad "1" smd circle
			(at -0.40005 0 270)
			(size 0 0)
			(layers "F.Cu" "F.Mask" "F.Paste")
			(net "P3V3")
		)
		(pad "2" smd circle
			(at 0.40005 0 270)
			(size 0 0)
			(layers "F.Cu" "F.Mask" "F.Paste")
			(net "PU_9ZXL0851_0_7_100M")
		)
	)
	(footprint ""
		(layer "F.Cu")
		(at 325.342504 -70.844918 -90)
		(property "Reference" "PD50"
			(at 3.992118 2.100834 90)
			(unlocked yes)
			(layer "F.SilkS")
			(effects
				(font
					(size 0.7874 0.5842)
					(thickness 0.1524)
				)
				(justify left)
			)
		)
		(property "Value" ""
			(at 0 0 270)
			(layer "F.Fab")
			(effects
				(font
					(size 1.27 1.27)
				)
			)
		)
		(duplicate_pad_numbers_are_jumpers no)
		(fp_line
			(start -3.400044 1.459992)
			(end -3.400044 -1.459992)
			(stroke
				(width 0.1524)
				(type default)
			)
			(layer "F.SilkS")
		)
		(fp_line
			(start 4.107942 1.459992)
			(end -3.400044 1.459992)
			(stroke
				(width 0.1524)
				(type default)
			)
			(layer "F.SilkS")
		)
		(fp_line
			(start -3.400044 -1.459992)
			(end 4.107942 -1.459992)
			(stroke
				(width 0.1524)
				(type default)
			)
			(layer "F.SilkS")
		)
		(fp_line
			(start 4.107942 -1.459992)
			(end 4.107942 1.459992)
			(stroke
				(width 0.1524)
				(type default)
			)
			(layer "F.SilkS")
		)
		(fp_poly
			(pts
				(xy 4.107942 -1.459992) (xy 4.107942 1.459992) (xy 3.308096 1.459992) (xy 3.308096 -1.459992)
			)
			(stroke
				(width 0)
				(type default)
			)
			(fill yes)
			(layer "F.SilkS")
		)
		(fp_line
			(start -2.29997 1.459992)
			(end -2.29997 -1.459992)
			(stroke
				(width 0.1)
				(type default)
			)
			(layer "F.Fab")
		)
		(fp_line
			(start 2.29997 1.459992)
			(end -2.29997 1.459992)
			(stroke
				(width 0.1)
				(type default)
			)
			(layer "F.Fab")
		)
		(fp_line
			(start -2.29997 -1.459992)
			(end 2.29997 -1.459992)
			(stroke
				(width 0.1)
				(type default)
			)
			(layer "F.Fab")
		)
		(fp_line
			(start 2.29997 -1.459992)
			(end 2.29997 1.459992)
			(stroke
				(width 0.1)
				(type default)
			)
			(layer "F.Fab")
		)
		(fp_text user "-"
			(at 5.4102 0.29845 90)
			(unlocked yes)
			(layer "F.SilkS")
			(effects
				(font
					(size 1.905 1.4224)
					(thickness 0.1524)
				)
				(justify left)
			)
		)
		(fp_text user "+"
			(at -5.257546 -0.23622 270)
			(unlocked yes)
			(layer "F.SilkS")
			(effects
				(font
					(size 1.905 1.4224)
					(thickness 0.1524)
				)
				(justify left)
			)
		)
		(fp_text user "-"
			(at 5.4102 0.29845 90)
			(unlocked yes)
			(layer "F.Fab")
			(effects
				(font
					(size 1.905 1.4224)
					(thickness 0.1524)
				)
				(justify left)
			)
		)
		(fp_text user "+"
			(at -4.7752 -0.12065 270)
			(unlocked yes)
			(layer "F.Fab")
			(effects
				(font
					(size 1.905 1.4224)
					(thickness 0.1524)
				)
				(justify left)
			)
		)
		(pad "A" smd rect
			(at -1.999996 0)
			(size 1.7018 2.5146)
			(layers "F.Cu" "F.Mask" "F.Paste")
			(net "GND")
		)
		(pad "C" smd rect
			(at 1.999996 0)
			(size 1.7018 2.5146)
			(layers "F.Cu" "F.Mask" "F.Paste")
			(net "P12V_SSD11_R")
		)
	)
	(footprint ""
		(layer "F.Cu")
		(at 209.926936 -188.652404 90)
		(property "Reference" "R5304"
			(at 0 0 90)
			(layer "F.SilkS")
			(hide yes)
			(effects
				(font
					(size 1.27 1.27)
				)
			)
		)
		(property "Value" ""
			(at 0 0 90)
			(layer "F.Fab")
			(effects
				(font
					(size 1.27 1.27)
				)
			)
		)
		(duplicate_pad_numbers_are_jumpers no)
		(fp_line
			(start 0.7874 -0.4064)
			(end 0.7874 0.4064)
			(stroke
				(width 0.1524)
				(type default)
			)
			(layer "F.SilkS")
		)
		(fp_line
			(start -0.7874 -0.4064)
			(end 0.7874 -0.4064)
			(stroke
				(width 0.1524)
				(type default)
			)
			(layer "F.SilkS")
		)
		(fp_line
			(start 0.7874 0.4064)
			(end -0.7874 0.4064)
			(stroke
				(width 0.1524)
				(type default)
			)
			(layer "F.SilkS")
		)
		(fp_line
			(start -0.7874 0.4064)
			(end -0.7874 -0.4064)
			(stroke
				(width 0.1524)
				(type default)
			)
			(layer "F.SilkS")
		)
		(fp_line
			(start -0.12065 -0.305054)
			(end -0.12065 -0.2794)
			(stroke
				(width 0.1)
				(type default)
			)
			(layer "F.Fab")
		)
		(fp_line
			(start -0.67945 -0.305054)
			(end -0.12065 -0.305054)
			(stroke
				(width 0.1)
				(type default)
			)
			(layer "F.Fab")
		)
		(fp_line
			(start 0.67945 -0.3048)
			(end 0.67945 0.3048)
			(stroke
				(width 0.1)
				(type default)
			)
			(layer "F.Fab")
		)
		(fp_line
			(start 0.12065 -0.3048)
			(end 0.67945 -0.3048)
			(stroke
				(width 0.1)
				(type default)
			)
			(layer "F.Fab")
		)
		(fp_line
			(start 0.12065 -0.2794)
			(end 0.12065 -0.3048)
			(stroke
				(width 0.1)
				(type default)
			)
			(layer "F.Fab")
		)
		(fp_line
			(start -0.12065 -0.2794)
			(end 0.12065 -0.2794)
			(stroke
				(width 0.1)
				(type default)
			)
			(layer "F.Fab")
		)
		(fp_line
			(start 0.120396 0.2794)
			(end -0.12065 0.2794)
			(stroke
				(width 0.1)
				(type default)
			)
			(layer "F.Fab")
		)
		(fp_line
			(start -0.12065 0.2794)
			(end -0.12065 0.3048)
			(stroke
				(width 0.1)
				(type default)
			)
			(layer "F.Fab")
		)
		(fp_line
			(start 0.67945 0.3048)
			(end 0.120396 0.3048)
			(stroke
				(width 0.1)
				(type default)
			)
			(layer "F.Fab")
		)
		(fp_line
			(start 0.120396 0.3048)
			(end 0.120396 0.2794)
			(stroke
				(width 0.1)
				(type default)
			)
			(layer "F.Fab")
		)
		(fp_line
			(start -0.12065 0.3048)
			(end -0.67945 0.3048)
			(stroke
				(width 0.1)
				(type default)
			)
			(layer "F.Fab")
		)
		(fp_line
			(start -0.67945 0.3048)
			(end -0.67945 -0.305054)
			(stroke
				(width 0.1)
				(type default)
			)
			(layer "F.Fab")
		)
		(pad "1" smd circle
			(at -0.40005 0 90)
			(size 0 0)
			(layers "F.Cu" "F.Mask" "F.Paste")
			(net "BIC_SEL_FLASH_SW3_R")
		)
		(pad "2" smd circle
			(at 0.40005 0 90)
			(size 0 0)
			(layers "F.Cu" "F.Mask" "F.Paste")
			(net "P3V3_AUX")
		)
	)
	(footprint ""
		(layer "F.Cu")
		(at 163.075112 -350.098614 90)
		(property "Reference" "C2513"
			(at 0 0 90)
			(layer "F.SilkS")
			(hide yes)
			(effects
				(font
					(size 1.27 1.27)
				)
			)
		)
		(property "Value" ""
			(at 0 0 90)
			(layer "F.Fab")
			(effects
				(font
					(size 1.27 1.27)
				)
			)
		)
		(duplicate_pad_numbers_are_jumpers no)
		(fp_line
			(start 0.299974 -0.150114)
			(end 0.299974 0.150114)
			(stroke
				(width 0.1)
				(type default)
			)
			(layer "F.Fab")
		)
		(fp_line
			(start -0.299974 -0.150114)
			(end 0.299974 -0.150114)
			(stroke
				(width 0.1)
				(type default)
			)
			(layer "F.Fab")
		)
		(fp_line
			(start 0.299974 0.150114)
			(end -0.299974 0.150114)
			(stroke
				(width 0.1)
				(type default)
			)
			(layer "F.Fab")
		)
		(fp_line
			(start -0.299974 0.150114)
			(end -0.299974 -0.150114)
			(stroke
				(width 0.1)
				(type default)
			)
			(layer "F.Fab")
		)
		(pad "1" smd rect
			(at -0.2667 0 90)
			(size 0.3048 0.381)
			(layers "F.Cu" "F.Mask" "F.Paste")
			(net "P5E_PEX1_STN4_TX_DN<79>")
		)
		(pad "2" smd rect
			(at 0.2667 0 90)
			(size 0.3048 0.381)
			(layers "F.Cu" "F.Mask" "F.Paste")
			(net "P5E_PEX1_STN4_TX_C_DN<79>")
		)
	)
)
